(kicad_pcb
	(version 20241229)
	(generator "pcbnew")
	(generator_version "9.0")
	(general
		(thickness 1.6)
		(legacy_teardrops no)
	)
	(paper "A4")
	(title_block
		(title "LPDDR4 testbed")
		(date "2024-03-26")
		(rev "1.2.2")
		(comment 9 "footprint 1 of 66 (J1), pads 198-262 of 262")
	)
	(layers
		(0 "F.Cu" signal)
		(4 "In1.Cu" power)
		(6 "In2.Cu" power)
		(8 "In3.Cu" signal)
		(10 "In4.Cu" signal)
		(2 "B.Cu" signal)
		(9 "F.Adhes" user "F.Adhesive")
		(11 "B.Adhes" user "B.Adhesive")
		(13 "F.Paste" user)
		(15 "B.Paste" user)
		(5 "F.SilkS" user "F.Silkscreen")
		(7 "B.SilkS" user "B.Silkscreen")
		(1 "F.Mask" user)
		(3 "B.Mask" user)
		(17 "Dwgs.User" user "User.Drawings")
		(19 "Cmts.User" user "User.Comments")
		(21 "Eco1.User" user "User.Eco1")
		(23 "Eco2.User" user "User.Eco2")
		(25 "Edge.Cuts" user)
		(27 "Margin" user)
		(31 "F.CrtYd" user "F.Courtyard")
		(29 "B.CrtYd" user "B.Courtyard")
		(35 "F.Fab" user)
		(33 "B.Fab" user)
	)
	(footprint "antmicro-footprints:Edge_Conn_Bus_DDR4"
		(locked yes)
		(layer "F.Cu")
		(at 100 100)
		(descr "SODIMM DDR4 Edge Connector")
		(tags "SODIMM DDR4 Edge Connector")
		(property "Reference" "J1"
			(at 0 -4.2 0)
			(layer "F.SilkS")
			(hide yes)
			(effects
				(font
					(size 0.7 0.7)
					(thickness 0.15)
				)
				(justify left bottom)
			)
		)
		(property "Value" "Bus_DDR4_Edge_Conn"
			(at 0 1 0)
			(layer "F.Fab")
			(effects
				(font
					(size 0.7 0.7)
					(thickness 0.15)
				)
				(justify left bottom)
			)
		)
		(property "Description" "DDR SO-DIMM PCB Edge"
			(at 0 0 0)
			(layer "F.Fab")
			(hide yes)
			(effects
				(font
					(size 1.27 1.27)
					(thickness 0.15)
				)
			)
		)
		(property "Author" "Antmicro"
			(at 0 0 0)
			(layer "F.Fab")
			(hide yes)
			(effects
				(font
					(size 1 1)
					(thickness 0.15)
				)
			)
		)
		(property "License" "Apache-2.0"
			(at 0 0 0)
			(layer "F.Fab")
			(hide yes)
			(effects
				(font
					(size 1 1)
					(thickness 0.15)
				)
			)
		)
		(property "MPN" ""
			(at 0 0 0)
			(layer "F.Fab")
			(hide yes)
			(effects
				(font
					(size 1 1)
					(thickness 0.15)
				)
			)
		)
		(property "Manufacturer" ""
			(at 0 0 0)
			(layer "F.Fab")
			(hide yes)
			(effects
				(font
					(size 1 1)
					(thickness 0.15)
				)
			)
		)
		(sheetname "SODIMM")
		(sheetfile "sodim.kicad_sch")
		(attr exclude_from_pos_files exclude_from_bom)
		(pad "196" smd rect
			(at 52.173 -1.301)
			(size 0.35 2.5)
			(layers "B.Cu" "B.Mask")
			(net 199 "CKE0_A")
			(pinfunction "196")
			(pintype "passive")
		)
		(pad "197" smd rect
			(at 52.423 -1.301)
			(size 0.35 2.5)
			(layers "F.Cu" "F.Mask")
			(net 201 "DMI_0A")
			(pinfunction "197")
			(pintype "passive")
		)
		(pad "198" smd rect
			(at 52.673 -1.301)
			(size 0.35 2.5)
			(layers "B.Cu" "B.Mask")
			(net 102 "unconnected-(J1-Pad198)")
			(pinfunction "198")
			(pintype "passive+no_connect")
		)
		(pad "199" smd rect
			(at 52.923 -1.301)
			(size 0.35 2.5)
			(layers "F.Cu" "F.Mask")
			(net 197 "DQ_S0_CA")
			(pinfunction "199")
			(pintype "passive")
		)
		(pad "200" smd rect
			(at 53.173 -1.301)
			(size 0.35 2.5)
			(layers "B.Cu" "B.Mask")
			(net 36 "GND")
			(pinfunction "200")
			(pintype "passive")
		)
		(pad "201" smd rect
			(at 53.423 -1.301)
			(size 0.35 2.5)
			(layers "F.Cu" "F.Mask")
			(net 196 "DQ_S0_TA")
			(pinfunction "201")
			(pintype "passive")
		)
		(pad "202" smd rect
			(at 53.673 -1.301)
			(size 0.35 2.5)
			(layers "B.Cu" "B.Mask")
			(net 103 "unconnected-(J1-Pad202)")
			(pinfunction "202")
			(pintype "passive+no_connect")
		)
		(pad "203" smd rect
			(at 53.923 -1.301)
			(size 0.35 2.5)
			(layers "F.Cu" "F.Mask")
			(net 190 "DQ00_A")
			(pinfunction "203")
			(pintype "passive")
		)
		(pad "204" smd rect
			(at 54.173 -1.301)
			(size 0.35 2.5)
			(layers "B.Cu" "B.Mask")
			(net 192 "CA0_A")
			(pinfunction "204")
			(pintype "passive")
		)
		(pad "205" smd rect
			(at 54.423 -1.301)
			(size 0.35 2.5)
			(layers "F.Cu" "F.Mask")
			(net 191 "DQ01_A")
			(pinfunction "205")
			(pintype "passive")
		)
		(pad "206" smd rect
			(at 54.673 -1.301)
			(size 0.35 2.5)
			(layers "B.Cu" "B.Mask")
			(net 194 "CA1_A")
			(pinfunction "206")
			(pintype "passive")
		)
		(pad "207" smd rect
			(at 54.923 -1.301)
			(size 0.35 2.5)
			(layers "F.Cu" "F.Mask")
			(net 193 "DQ02_A")
			(pinfunction "207")
			(pintype "passive")
		)
		(pad "208" smd rect
			(at 55.173 -1.301)
			(size 0.35 2.5)
			(layers "B.Cu" "B.Mask")
			(net 104 "unconnected-(J1-Pad208)")
			(pinfunction "208")
			(pintype "passive+no_connect")
		)
		(pad "209" smd rect
			(at 55.423 -1.301)
			(size 0.35 2.5)
			(layers "F.Cu" "F.Mask")
			(net 195 "DQ03_A")
			(pinfunction "209")
			(pintype "passive")
		)
		(pad "210" smd rect
			(at 55.673 -1.301)
			(size 0.35 2.5)
			(layers "B.Cu" "B.Mask")
			(net 36 "GND")
			(pinfunction "210")
			(pintype "passive")
		)
		(pad "211" smd rect
			(at 55.923 -1.301)
			(size 0.35 2.5)
			(layers "F.Cu" "F.Mask")
			(net 36 "GND")
			(pinfunction "211")
			(pintype "passive")
		)
		(pad "212" smd rect
			(at 56.173 -1.301)
			(size 0.35 2.5)
			(layers "B.Cu" "B.Mask")
			(net 105 "unconnected-(J1-Pad212)")
			(pinfunction "212")
			(pintype "passive+no_connect")
		)
		(pad "213" smd rect
			(at 56.423 -1.301)
			(size 0.35 2.5)
			(layers "F.Cu" "F.Mask")
			(net 106 "unconnected-(J1-Pad213)")
			(pinfunction "213")
			(pintype "passive+no_connect")
		)
		(pad "214" smd rect
			(at 56.673 -1.301)
			(size 0.35 2.5)
			(layers "B.Cu" "B.Mask")
			(net 107 "unconnected-(J1-Pad214)")
			(pinfunction "214")
			(pintype "passive+no_connect")
		)
		(pad "215" smd rect
			(at 56.923 -1.301)
			(size 0.35 2.5)
			(layers "F.Cu" "F.Mask")
			(net 108 "unconnected-(J1-Pad215)")
			(pinfunction "215")
			(pintype "passive+no_connect")
		)
		(pad "216" smd rect
			(at 57.173 -1.301)
			(size 0.35 2.5)
			(layers "B.Cu" "B.Mask")
			(net 109 "unconnected-(J1-Pad216)")
			(pinfunction "216")
			(pintype "passive+no_connect")
		)
		(pad "217" smd rect
			(at 57.423 -1.301)
			(size 0.35 2.5)
			(layers "F.Cu" "F.Mask")
			(net 110 "unconnected-(J1-Pad217)")
			(pinfunction "217")
			(pintype "passive+no_connect")
		)
		(pad "218" smd rect
			(at 57.673 -1.301)
			(size 0.35 2.5)
			(layers "B.Cu" "B.Mask")
			(net 111 "unconnected-(J1-Pad218)")
			(pinfunction "218")
			(pintype "passive+no_connect")
		)
		(pad "219" smd rect
			(at 57.923 -1.301)
			(size 0.35 2.5)
			(layers "F.Cu" "F.Mask")
			(net 112 "unconnected-(J1-Pad219)")
			(pinfunction "219")
			(pintype "passive+no_connect")
		)
		(pad "220" smd rect
			(at 58.173 -1.301)
			(size 0.35 2.5)
			(layers "B.Cu" "B.Mask")
			(net 113 "unconnected-(J1-Pad220)")
			(pinfunction "220")
			(pintype "passive+no_connect")
		)
		(pad "221" smd rect
			(at 58.423 -1.301)
			(size 0.35 2.5)
			(layers "F.Cu" "F.Mask")
			(net 114 "unconnected-(J1-Pad221)")
			(pinfunction "221")
			(pintype "passive+no_connect")
		)
		(pad "222" smd rect
			(at 58.673 -1.301)
			(size 0.35 2.5)
			(layers "B.Cu" "B.Mask")
			(net 115 "unconnected-(J1-Pad222)")
			(pinfunction "222")
			(pintype "passive+no_connect")
		)
		(pad "223" smd rect
			(at 58.923 -1.301)
			(size 0.35 2.5)
			(layers "F.Cu" "F.Mask")
			(net 116 "unconnected-(J1-Pad223)")
			(pinfunction "223")
			(pintype "passive+no_connect")
		)
		(pad "224" smd rect
			(at 59.173 -1.301)
			(size 0.35 2.5)
			(layers "B.Cu" "B.Mask")
			(net 117 "unconnected-(J1-Pad224)")
			(pinfunction "224")
			(pintype "passive+no_connect")
		)
		(pad "225" smd rect
			(at 59.423 -1.301)
			(size 0.35 2.5)
			(layers "F.Cu" "F.Mask")
			(net 118 "unconnected-(J1-Pad225)")
			(pinfunction "225")
			(pintype "passive+no_connect")
		)
		(pad "226" smd rect
			(at 59.673 -1.301)
			(size 0.35 2.5)
			(layers "B.Cu" "B.Mask")
			(net 119 "unconnected-(J1-Pad226)")
			(pinfunction "226")
			(pintype "passive+no_connect")
		)
		(pad "227" smd rect
			(at 59.923 -1.301)
			(size 0.35 2.5)
			(layers "F.Cu" "F.Mask")
			(net 120 "unconnected-(J1-Pad227)")
			(pinfunction "227")
			(pintype "passive+no_connect")
		)
		(pad "228" smd rect
			(at 60.173 -1.301)
			(size 0.35 2.5)
			(layers "B.Cu" "B.Mask")
			(net 121 "unconnected-(J1-Pad228)")
			(pinfunction "228")
			(pintype "passive+no_connect")
		)
		(pad "229" smd rect
			(at 60.423 -1.301)
			(size 0.35 2.5)
			(layers "F.Cu" "F.Mask")
			(net 122 "unconnected-(J1-Pad229)")
			(pinfunction "229")
			(pintype "passive+no_connect")
		)
		(pad "230" smd rect
			(at 60.673 -1.301)
			(size 0.35 2.5)
			(layers "B.Cu" "B.Mask")
			(net 123 "unconnected-(J1-Pad230)")
			(pinfunction "230")
			(pintype "passive+no_connect")
		)
		(pad "231" smd rect
			(at 60.923 -1.301)
			(size 0.35 2.5)
			(layers "F.Cu" "F.Mask")
			(net 124 "unconnected-(J1-Pad231)")
			(pinfunction "231")
			(pintype "passive+no_connect")
		)
		(pad "232" smd rect
			(at 61.173 -1.301)
			(size 0.35 2.5)
			(layers "B.Cu" "B.Mask")
			(net 125 "unconnected-(J1-Pad232)")
			(pinfunction "232")
			(pintype "passive+no_connect")
		)
		(pad "233" smd rect
			(at 61.423 -1.301)
			(size 0.35 2.5)
			(layers "F.Cu" "F.Mask")
			(net 126 "unconnected-(J1-Pad233)")
			(pinfunction "233")
			(pintype "passive+no_connect")
		)
		(pad "234" smd rect
			(at 61.673 -1.301)
			(size 0.35 2.5)
			(layers "B.Cu" "B.Mask")
			(net 127 "unconnected-(J1-Pad234)")
			(pinfunction "234")
			(pintype "passive+no_connect")
		)
		(pad "235" smd rect
			(at 61.923 -1.301)
			(size 0.35 2.5)
			(layers "F.Cu" "F.Mask")
			(net 128 "unconnected-(J1-Pad235)")
			(pinfunction "235")
			(pintype "passive+no_connect")
		)
		(pad "236" smd rect
			(at 62.173 -1.301)
			(size 0.35 2.5)
			(layers "B.Cu" "B.Mask")
			(net 129 "unconnected-(J1-Pad236)")
			(pinfunction "236")
			(pintype "passive+no_connect")
		)
		(pad "237" smd rect
			(at 62.423 -1.301)
			(size 0.35 2.5)
			(layers "F.Cu" "F.Mask")
			(net 130 "unconnected-(J1-Pad237)")
			(pinfunction "237")
			(pintype "passive+no_connect")
		)
		(pad "238" smd rect
			(at 62.673 -1.301)
			(size 0.35 2.5)
			(layers "B.Cu" "B.Mask")
			(net 131 "unconnected-(J1-Pad238)")
			(pinfunction "238")
			(pintype "passive+no_connect")
		)
		(pad "239" smd rect
			(at 62.923 -1.301)
			(size 0.35 2.5)
			(layers "F.Cu" "F.Mask")
			(net 132 "unconnected-(J1-Pad239)")
			(pinfunction "239")
			(pintype "passive+no_connect")
		)
		(pad "240" smd rect
			(at 63.173 -1.301)
			(size 0.35 2.5)
			(layers "B.Cu" "B.Mask")
			(net 133 "unconnected-(J1-Pad240)")
			(pinfunction "240")
			(pintype "passive+no_connect")
		)
		(pad "241" smd rect
			(at 63.423 -1.301)
			(size 0.35 2.5)
			(layers "F.Cu" "F.Mask")
			(net 134 "unconnected-(J1-Pad241)")
			(pinfunction "241")
			(pintype "passive+no_connect")
		)
		(pad "242" smd rect
			(at 63.673 -1.301)
			(size 0.35 2.5)
			(layers "B.Cu" "B.Mask")
			(net 135 "unconnected-(J1-Pad242)")
			(pinfunction "242")
			(pintype "passive+no_connect")
		)
		(pad "243" smd rect
			(at 63.923 -1.301)
			(size 0.35 2.5)
			(layers "F.Cu" "F.Mask")
			(net 136 "unconnected-(J1-Pad243)")
			(pinfunction "243")
			(pintype "passive+no_connect")
		)
		(pad "244" smd rect
			(at 64.174 -1.301)
			(size 0.35 2.5)
			(layers "B.Cu" "B.Mask")
			(net 137 "unconnected-(J1-Pad244)")
			(pinfunction "244")
			(pintype "passive+no_connect")
		)
		(pad "245" smd rect
			(at 64.424 -1.301)
			(size 0.35 2.5)
			(layers "F.Cu" "F.Mask")
			(net 138 "unconnected-(J1-Pad245)")
			(pinfunction "245")
			(pintype "passive+no_connect")
		)
		(pad "246" smd rect
			(at 64.674 -1.301)
			(size 0.35 2.5)
			(layers "B.Cu" "B.Mask")
			(net 189 "VDDQ")
			(pinfunction "246")
			(pintype "passive")
		)
		(pad "247" smd rect
			(at 64.924 -1.301)
			(size 0.35 2.5)
			(layers "F.Cu" "F.Mask")
			(net 139 "unconnected-(J1-Pad247)")
			(pinfunction "247")
			(pintype "passive+no_connect")
		)
		(pad "248" smd rect
			(at 65.174 -1.301)
			(size 0.35 2.5)
			(layers "B.Cu" "B.Mask")
			(net 189 "VDDQ")
			(pinfunction "248")
			(pintype "passive")
		)
		(pad "249" smd rect
			(at 65.424 -1.301)
			(size 0.35 2.5)
			(layers "F.Cu" "F.Mask")
			(net 140 "unconnected-(J1-Pad249)")
			(pinfunction "249")
			(pintype "passive+no_connect")
		)
		(pad "250" smd rect
			(at 65.674 -1.301)
			(size 0.35 2.5)
			(layers "B.Cu" "B.Mask")
			(net 189 "VDDQ")
			(pinfunction "250")
			(pintype "passive")
		)
		(pad "251" smd rect
			(at 65.924 -1.301)
			(size 0.35 2.5)
			(layers "F.Cu" "F.Mask")
			(net 141 "unconnected-(J1-Pad251)")
			(pinfunction "251")
			(pintype "passive+no_connect")
		)
		(pad "252" smd rect
			(at 66.174 -1.301)
			(size 0.35 2.5)
			(layers "B.Cu" "B.Mask")
			(net 142 "unconnected-(J1-Pad252)")
			(pinfunction "252")
			(pintype "passive+no_connect")
		)
		(pad "253" smd rect
			(at 66.424 -1.301)
			(size 0.35 2.5)
			(layers "F.Cu" "F.Mask")
			(net 143 "unconnected-(J1-Pad253)")
			(pinfunction "253")
			(pintype "passive+no_connect")
		)
		(pad "254" smd rect
			(at 66.674 -1.301)
			(size 0.35 2.5)
			(layers "B.Cu" "B.Mask")
			(net 144 "unconnected-(J1-Pad254)")
			(pinfunction "254")
			(pintype "passive+no_connect")
		)
		(pad "255" smd rect
			(at 66.924 -1.301)
			(size 0.35 2.5)
			(layers "F.Cu" "F.Mask")
			(net 145 "unconnected-(J1-Pad255)")
			(pinfunction "255")
			(pintype "passive+no_connect")
		)
		(pad "256" smd rect
			(at 67.174 -1.301)
			(size 0.35 2.5)
			(layers "B.Cu" "B.Mask")
			(net 146 "unconnected-(J1-Pad256)")
			(pinfunction "256")
			(pintype "passive+no_connect")
		)
		(pad "257" smd rect
			(at 67.424 -1.301)
			(size 0.35 2.5)
			(layers "F.Cu" "F.Mask")
			(net 147 "unconnected-(J1-Pad257)")
			(pinfunction "257")
			(pintype "passive+no_connect")
		)
		(pad "258" smd rect
			(at 67.674 -1.301)
			(size 0.35 2.5)
			(layers "B.Cu" "B.Mask")
			(net 148 "unconnected-(J1-Pad258)")
			(pinfunction "258")
			(pintype "passive+no_connect")
		)
		(pad "259" smd rect
			(at 67.924 -1.301)
			(size 0.35 2.5)
			(layers "F.Cu" "F.Mask")
			(net 149 "unconnected-(J1-Pad259)")
			(pinfunction "259")
			(pintype "passive+no_connect")
		)
		(pad "260" smd rect
			(at 68.174 -1.301)
			(size 0.35 2.5)
			(layers "B.Cu" "B.Mask")
			(net 150 "unconnected-(J1-Pad260)")
			(pinfunction "260")
			(pintype "passive+no_connect")
		)
	)
)
